FILE_TYPE = CONNECTIVITY;
{Allegro Design Entry HDL 16.6-p007 (v16-6-112F) 10/10/2012}
"PAGE_NUMBER" = 162;
0"NC";
1"P3V3_STBY\g";
2"GND\g";
3"GND\g";
4"GND\g";
5"TP_SPI_2_2";
6"TP_SPI_2_4";
7"SPI_BMC_BT_CS_N";
8"SPI_BMC_BT_CLK";
9"PU_SPI_FLASH_RESET_2_N";
10"TP_SPI_2_3";
11"TP_SPI_2_5";
12"SPI_BMC_BT_DI";
13"TP_SPI_2_0";
14"TP_SPI_2_6";
15"PU_SPI_BMC_BT_HOLD_N";
16"SPI_BMC_BT_DI_R";
17"PU_SPI_BMC_BT_WP_N";
18"SPI_BMC_BT_DO";
19"TP_SPI_2_1";
%"P3V3_STBY"
"1","(5250,3700)","0","mstr_symbols","I10";
;
VOLTAGE"3.3V"
CDS_LIB"mstr_symbols"
SIZE"1B"
BODY_TYPE"PLUMBING"
HDL_POWER"P3V3_STBY";
"G\NAC"1;
%"RES"
"1","(5075,2550)","0","mstr_discrete","I13";
;
CDS_SEC"1"
LOCATION"R8F12"
VALUE"33.2"
TOLERANCE"1%"
MATERIAL"CHIP"
PART_NUMBER"G21796-074"
PACK_TYPE"0402"
WATTAGE"1/16W"
CDS_LOCATION"R8F12"
CDS_LIB"mstr_discrete"
SEC_TYPE"0402"
SEC"1"
ROOM"BMC_BOOT_SPI"
BOM_COST"SM_MEM";
"B"
$PN"2"16;
"A"
$PN"1"12;
%"RES"
"2","(4825,3325)","2","mstr_discrete","I22";
;
CDS_SEC"1"
TOLERANCE"1%"
LOCATION"R8F34"
VALUE"4.75K"
MATERIAL"CHIP"
WATTAGE"1/16W"
PACK_TYPE"0402"
PART_NUMBER"G21796-072"
SEC_TYPE"0402"
SEC"1"
BOM_COST"SM_MEM"
ROOM"BMC_BOOT_SPI"
CDS_LOCATION"R8F34"
CDS_LIB"mstr_discrete";
"A"
$PN"1"1;
"B"
$PN"2"17;
%"RES"
"2","(4875,2050)","0","mstr_discrete","I24";
;
CDS_SEC"1"
TOLERANCE"1%"
PACK_TYPE"0402"
PART_NUMBER"G21796-026"
MATERIAL"EMPTY"
WATTAGE"1/16W"
VALUE"1.00K"
LOCATION"R8F35"
CDS_LIB"mstr_discrete"
CDS_LOCATION"R8F35"
ROOM"BMC_BOOT_SPI"
BOM_COST"SM_MEM"
SEC"1"
SEC_TYPE"0402";
"A"
$PN"1"17;
"B"
$PN"2"3;
%"CAP_A"
"1","(7650,3400)","0","dev_discrete","I28";
;
CDS_SEC"1"
MATERIAL"X7R"
LOCATION"C8F5"
PART_NUMBER"A36096-045"
TOLERANCE"10%"
PACK_TYPE"0402V"
VOLTAGE"25V"
VALUE"0.01UF"
CDS_LIB"dev_discrete"
CDS_LOCATION"C8F5"
ROOM"BMC_BOOT_SPI"
BOM_COST"SM_MEM"
SEC"1"
SEC_TYPE"0402V";
"B"
$PN"2"2;
"A"
$PN"1"1;
%"CAP_A"
"1","(7350,3400)","0","dev_discrete","I30";
;
CDS_SEC"1"
VOLTAGE"6.3V"
VALUE"1.0UF"
LOCATION"C8F4"
MATERIAL"X6S"
TOLERANCE"10%"
PACK_TYPE"0402V"
PART_NUMBER"D97712-004"
CDS_LIB"dev_discrete"
CDS_LOCATION"C8F4"
ROOM"BMC_BOOT_SPI"
BOM_COST"SM_MEM"
SEC"1"
SEC_TYPE"0402V";
"B"
$PN"2"2;
"A"
$PN"1"1;
%"GND"
"1","(7650,3075)","0","mstr_symbols","I31";
;
VOLTAGE"0.0V"
SIZE"1B"
CDS_LIB"mstr_symbols"
BODY_TYPE"PLUMBING"
HDL_POWER"GND";
"A\NAC"2;
%"W25Q128"
"3","(6450,2800)","0","mstr_memory","I32";
;
CDS_SEC"1"
MATERIAL"IC"
LOCATION"U8F2"
PART_NUMBER"H12709-001"
ROOM"BMC_BOOT_SPI"
CDS_LOCATION"U8F2"
SEC"1"
BOM_COST"SM_MEM"
SEC_TYPE"SKT16"
PACK_TYPE"SKT16"
CDS_LMAN_SYM_OUTLINE"-500,325,500,-325"
CDS_LIB"mstr_memory";
"DI_IO<0>"
$PN"15"18;
"WP_N_IO<2> \B"
$PN"9"17;
"VCC"
$PN"2"1;
"NC<6>"
$PN"14"14;
"NC<5>"
$PN"13"11;
"NC<4>"
$PN"12"6;
"NC<3>"
$PN"11"10;
"GND"
$PN"10"4;
"NC<2>"
$PN"6"5;
"NC<1>"
$PN"5"19;
"NC<0>"
$PN"4"13;
"DO_IO<1>"
$PN"8"16;
"HOLD_N_IO<3> \B"
$PN"1"15;
"CS_N \B"
$PN"7"7;
"CLK"
$PN"16"8;
"RESET_N \B"
$PN"3"9;
%"GND"
"1","(4875,1750)","0","mstr_symbols","I33";
;
VOLTAGE"0.0V"
CDS_LIB"mstr_symbols"
SIZE"1B"
BODY_TYPE"PLUMBING"
HDL_POWER"GND";
"A\NAC"3;
%"RES"
"2","(4550,3325)","2","mstr_discrete","I35";
;
CDS_SEC"1"
TOLERANCE"1%"
LOCATION"R8F13"
VALUE"4.75K"
MATERIAL"CHIP"
WATTAGE"1/16W"
PART_NUMBER"G21796-072"
PACK_TYPE"0402"
SEC_TYPE"0402"
SEC"1"
BOM_COST"SM_MEM"
ROOM"BMC_BOOT_SPI"
CDS_LIB"mstr_discrete"
CDS_LOCATION"R8F13";
"A"
$PN"1"1;
"B"
$PN"2"7;
%"GND"
"1","(7100,2350)","0","mstr_symbols","I6";
;
VOLTAGE"0"
CDS_LIB"mstr_symbols"
SIZE"1B"
BODY_TYPE"PLUMBING"
HDL_POWER"GND";
"A\NAC"4;
%"RES"
"2","(5300,3300)","0","mstr_discrete","I8";
;
CDS_SEC"1"
TOLERANCE"1%"
PACK_TYPE"0402"
PART_NUMBER"G21796-072"
WATTAGE"1/16W"
MATERIAL"EMPTY"
LOCATION"R8F16"
VALUE"4.75K"
SEC_TYPE"0402"
BOM_COST"SM_MEM"
SEC"1"
ROOM"BMC_BOOT_SPI"
CDS_LOCATION"R8F16"
CDS_LIB"mstr_discrete";
"A"
$PN"1"1;
"B"
$PN"2"9;
%"RES"
"2","(5100,3325)","2","mstr_discrete","I9";
;
CDS_SEC"1"
LOCATION"R8F14"
VALUE"4.75K"
MATERIAL"CHIP"
TOLERANCE"1%"
WATTAGE"1/16W"
PACK_TYPE"0402"
PART_NUMBER"G21796-072"
CDS_LIB"mstr_discrete"
CDS_LOCATION"R8F14"
SEC"1"
ROOM"BMC_BOOT_SPI"
BOM_COST"SM_MEM"
SEC_TYPE"0402";
"A"
$PN"1"1;
"B"
$PN"2"15;
END.
